#ISCELL
  mstr_symbols bom_note *
  *
#ISCELL
  mstr_symbols intel_corp_bpage *
  *
#ISCELL
  mstr_standard offpage *
  page82_i1
#ISCELL
  mstr_standard tap *
  page82_i10
#ISCELL
  mstr_standard tap *
  page82_i100
#ISCELL
  mstr_standard tap *
  page82_i101
#ISCELL
  mstr_standard tap *
  page82_i102
#ISCELL
  mstr_standard tap *
  page82_i103
#ISCELL
  mstr_standard tap *
  page82_i104
#ISCELL
  mstr_standard tap *
  page82_i105
#ISCELL
  mstr_standard tap *
  page82_i106
#ISCELL
  mstr_standard tap *
  page82_i107
#ISCELL
  mstr_standard tap *
  page82_i108
#ISCELL
  mstr_standard tap *
  page82_i109
#ISCELL
  mstr_standard tap *
  page82_i11
#ISCELL
  mstr_standard tap *
  page82_i110
#ISCELL
  mstr_standard tap *
  page82_i112
#ISCELL
  mstr_standard tap *
  page82_i113
#ISCELL
  mstr_standard tap *
  page82_i114
#ISCELL
  mstr_standard tap *
  page82_i115
#ISCELL
  mstr_standard tap *
  page82_i116
#ISCELL
  mstr_standard tap *
  page82_i117
#ISCELL
  mstr_standard tap *
  page82_i118
#ISCELL
  mstr_standard tap *
  page82_i119
#ISCELL
  mstr_standard tap *
  page82_i12
#ISCELL
  mstr_standard tap *
  page82_i120
#ISCELL
  mstr_standard tap *
  page82_i121
#ISCELL
  mstr_standard tap *
  page82_i122
#ISCELL
  mstr_standard tap *
  page82_i123
#ISCELL
  mstr_standard tap *
  page82_i124
#ISCELL
  mstr_standard tap *
  page82_i125
#ISCELL
  mstr_standard tap *
  page82_i126
#ISCELL
  mstr_standard tap *
  page82_i127
#ISCELL
  mstr_standard tap *
  page82_i128
#ISCELL
  mstr_standard tap *
  page82_i129
#ISCELL
  mstr_standard tap *
  page82_i13
#ISCELL
  mstr_standard offpage *
  page82_i130
#ISCELL
  mstr_standard tap *
  page82_i131
#ISCELL
  mstr_standard tap *
  page82_i132
#ISCELL
  mstr_standard tap *
  page82_i133
#ISCELL
  mstr_standard tap *
  page82_i134
#ISCELL
  mstr_standard offpage *
  page82_i135
#ISCELL
  mstr_standard offpage *
  page82_i136
#ISCELL
  mstr_standard offpage *
  page82_i137
#ISCELL
  mstr_standard tap *
  page82_i138
#ISCELL
  mstr_standard tap *
  page82_i139
#ISCELL
  mstr_symbols pvddq_ghj *
  page82_i14
#ISCELL
  mstr_standard tap *
  page82_i140
#ISCELL
  mstr_standard tap *
  page82_i141
#ISCELL
  mstr_standard tap *
  page82_i142
#ISCELL
  mstr_standard tap *
  page82_i143
#ISCELL
  mstr_standard tap *
  page82_i144
#ISCELL
  mstr_standard tap *
  page82_i145
#ISCELL
  mstr_standard offpage *
  page82_i146
#ISCELL
  mstr_standard offpage *
  page82_i147
#ISCELL
  mstr_standard offpage *
  page82_i148
#ISCELL
  mstr_standard offpage *
  page82_i149
#ISCELL
  mstr_standard offpage *
  page82_i150
#ISCELL
  mstr_standard tap *
  page82_i152
#ISCELL
  mstr_standard tap *
  page82_i153
#ISCELL
  mstr_standard tap *
  page82_i154
#ISCELL
  mstr_standard tap *
  page82_i155
#ISCELL
  mstr_standard offpage *
  page82_i156
#ISCELL
  mstr_standard offpage *
  page82_i157
#ISCELL
  mstr_standard tap *
  page82_i158
#ISCELL
  mstr_standard tap *
  page82_i159
#ISCELL
  mstr_symbols pvtt_ghj *
  page82_i16
#ISCELL
  mstr_standard tap *
  page82_i160
#ISCELL
  mstr_standard tap *
  page82_i161
#ISCELL
  mstr_standard tap *
  page82_i162
#ISCELL
  mstr_standard offpage *
  page82_i163
#ISCELL
  mstr_standard offpage *
  page82_i164
#ISCELL
  mstr_standard tap *
  page82_i165
#ISCELL
  mstr_standard tap *
  page82_i166
#ISCELL
  mstr_standard offpage *
  page82_i167
#ISCELL
  mstr_standard tap *
  page82_i168
#ISCELL
  mstr_standard tap *
  page82_i17
#CELL
  mstr_sconn sconn288_h44441003 *
  page82_i171
#ISCELL
  mstr_symbols gnd *
  page82_i172
#ISCELL
  mstr_standard offpage *
  page82_i173
#ISCELL
  mstr_standard offpage *
  page82_i174
#ISCELL
  mstr_standard offpage *
  page82_i175
#ISCELL
  mstr_standard offpage *
  page82_i178
#ISCELL
  mstr_symbols gnd *
  page82_i179
#ISCELL
  mstr_standard tap *
  page82_i18
#CELL
  dev_discrete cap_a *
  page82_i180
#ISCELL
  mstr_symbols pvpp_ghj *
  page82_i181
#ISCELL
  mstr_symbols pvpp_ghj *
  page82_i182
#ISCELL
  mstr_standard offpage *
  page82_i183
#CELL
  mstr_sconn sconn288_h44441003 *
  page82_i187
#CELL
  mstr_sconn sconn288_h44441003 *
  page82_i188
#ISCELL
  mstr_symbols gnd *
  page82_i189
#ISCELL
  mstr_standard tap *
  page82_i19
#ISCELL
  mstr_symbols p12v_nvdimm_ghj *
  page82_i190
#ISCELL
  mstr_standard offpage *
  page82_i2
#ISCELL
  mstr_standard tap *
  page82_i20
#ISCELL
  mstr_standard tap *
  page82_i21
#ISCELL
  mstr_standard tap *
  page82_i22
#ISCELL
  mstr_standard tap *
  page82_i23
#ISCELL
  mstr_standard tap *
  page82_i24
#ISCELL
  mstr_standard tap *
  page82_i25
#ISCELL
  mstr_standard tap *
  page82_i26
#ISCELL
  mstr_standard tap *
  page82_i27
#ISCELL
  mstr_standard tap *
  page82_i28
#ISCELL
  mstr_standard tap *
  page82_i29
#ISCELL
  mstr_standard tap *
  page82_i3
#ISCELL
  mstr_standard tap *
  page82_i30
#ISCELL
  mstr_standard tap *
  page82_i31
#ISCELL
  mstr_standard tap *
  page82_i32
#ISCELL
  mstr_standard tap *
  page82_i33
#ISCELL
  mstr_standard tap *
  page82_i34
#ISCELL
  mstr_standard tap *
  page82_i35
#ISCELL
  mstr_standard tap *
  page82_i36
#ISCELL
  mstr_standard tap *
  page82_i37
#ISCELL
  mstr_standard tap *
  page82_i38
#ISCELL
  mstr_standard tap *
  page82_i39
#ISCELL
  mstr_standard tap *
  page82_i4
#ISCELL
  mstr_standard tap *
  page82_i40
#ISCELL
  mstr_standard tap *
  page82_i41
#ISCELL
  mstr_symbols gnd *
  page82_i44
#ISCELL
  mstr_standard offpage *
  page82_i45
#ISCELL
  mstr_standard tap *
  page82_i46
#ISCELL
  mstr_standard tap *
  page82_i47
#ISCELL
  mstr_standard tap *
  page82_i48
#ISCELL
  mstr_standard tap *
  page82_i49
#ISCELL
  mstr_standard tap *
  page82_i5
#ISCELL
  mstr_standard tap *
  page82_i50
#ISCELL
  mstr_standard tap *
  page82_i51
#ISCELL
  mstr_standard tap *
  page82_i52
#ISCELL
  mstr_standard tap *
  page82_i53
#ISCELL
  mstr_standard tap *
  page82_i54
#ISCELL
  mstr_standard tap *
  page82_i55
#ISCELL
  mstr_standard tap *
  page82_i56
#ISCELL
  mstr_standard tap *
  page82_i57
#ISCELL
  mstr_standard tap *
  page82_i58
#ISCELL
  mstr_standard tap *
  page82_i59
#ISCELL
  mstr_standard tap *
  page82_i6
#ISCELL
  mstr_standard tap *
  page82_i60
#ISCELL
  mstr_standard tap *
  page82_i61
#ISCELL
  mstr_standard tap *
  page82_i62
#ISCELL
  mstr_standard tap *
  page82_i63
#CELL
  mstr_sconn sconn288_h44441003 *
  page82_i64
#ISCELL
  mstr_standard tap *
  page82_i65
#ISCELL
  mstr_standard tap *
  page82_i66
#ISCELL
  mstr_standard tap *
  page82_i67
#ISCELL
  mstr_standard tap *
  page82_i68
#ISCELL
  mstr_standard tap *
  page82_i69
#ISCELL
  mstr_standard tap *
  page82_i7
#ISCELL
  mstr_standard tap *
  page82_i70
#ISCELL
  mstr_standard tap *
  page82_i71
#ISCELL
  mstr_standard tap *
  page82_i72
#ISCELL
  mstr_standard tap *
  page82_i73
#ISCELL
  mstr_standard tap *
  page82_i74
#ISCELL
  mstr_standard tap *
  page82_i75
#ISCELL
  mstr_standard tap *
  page82_i76
#ISCELL
  mstr_standard tap *
  page82_i77
#ISCELL
  mstr_standard tap *
  page82_i78
#ISCELL
  mstr_standard tap *
  page82_i79
#ISCELL
  mstr_standard tap *
  page82_i8
#ISCELL
  mstr_standard tap *
  page82_i80
#ISCELL
  mstr_standard tap *
  page82_i81
#ISCELL
  mstr_standard tap *
  page82_i82
#ISCELL
  mstr_standard tap *
  page82_i83
#ISCELL
  mstr_standard tap *
  page82_i84
#ISCELL
  mstr_standard tap *
  page82_i85
#ISCELL
  mstr_standard tap *
  page82_i86
#ISCELL
  mstr_standard tap *
  page82_i87
#ISCELL
  mstr_standard tap *
  page82_i88
#ISCELL
  mstr_standard tap *
  page82_i89
#ISCELL
  mstr_standard tap *
  page82_i9
#ISCELL
  mstr_standard tap *
  page82_i90
#ISCELL
  mstr_standard tap *
  page82_i91
#ISCELL
  mstr_standard tap *
  page82_i92
#ISCELL
  mstr_standard tap *
  page82_i93
#ISCELL
  mstr_standard tap *
  page82_i94
#ISCELL
  mstr_standard tap *
  page82_i95
#ISCELL
  mstr_standard tap *
  page82_i96
#ISCELL
  mstr_standard tap *
  page82_i97
#ISCELL
  mstr_standard tap *
  page82_i98
#ISCELL
  mstr_standard tap *
  page82_i99
